# T6G (Grand Teton) — schematic netlist excerpt (pin names and nets, part order shuffled) for the footprints in the layout excerpt that follows; sources: Cadence DE-HDL packaged netlist, KiCad conversion of 04192023_DAF0TMB3IC0_F0TG_MB_C_brd_V02_OCP.brd

R6033  Q_RES  0 5% CHIP  pkg 0402LF  page 150 : A = RST_MB_STBY_N ; B = RST_MB_STBY_R_N
C2329  Q_CAP  0.1UF 25V 10% X7R  pkg 0402  page 182 : A = P3V3_9ZXL045_P0_VDD ; B = GND
C186  Q_CAP  1UF 4V 20% X6S  pkg 0201  page 323 : A = P0V9_CPU1_RT0_2A ; B = GND

(kicad_pcb
	(version 20260206)
	(generator "pcbnew")
	(generator_version "10.0")
	(general
		(thickness 1.6)
		(legacy_teardrops no)
	)
	(paper "A4")
	(title_block
		(title "04192023_DAF0TMB3IC0_F0TG_MB_C_brd_V02_OCP.brd")
		(comment 1 "Grand Teton / footprints 5475-5477 of 8354")
	)
	(layers
		(0 "F.Cu" signal "TOP")
		(4 "In1.Cu" signal "GND")
		(6 "In2.Cu" signal "IN1")
		(8 "In3.Cu" signal "GND1")
		(10 "In4.Cu" signal "IN2")
		(12 "In5.Cu" signal "GND2")
		(14 "In6.Cu" signal "IN3")
		(16 "In7.Cu" signal "GND3")
		(18 "In8.Cu" signal "VCC")
		(20 "In9.Cu" signal "VCC1")
		(22 "In10.Cu" signal "GND4")
		(24 "In11.Cu" signal "IN4")
		(26 "In12.Cu" signal "GND5")
		(28 "In13.Cu" signal "IN5")
		(30 "In14.Cu" signal "GND6")
		(32 "In15.Cu" signal "IN6")
		(34 "In16.Cu" signal "GND7")
		(2 "B.Cu" signal "BOTTOM")
		(9 "F.Adhes" user "F.Adhesive")
		(11 "B.Adhes" user "B.Adhesive")
		(13 "F.Paste" user "Package Geometry/Pastemask Top")
		(15 "B.Paste" user "Package Geometry/Pastemask Bottom")
		(5 "F.SilkS" user "Ref Des/Silkscreen Top")
		(7 "B.SilkS" user "Ref Des/Silkscreen Bottom")
		(1 "F.Mask" user "Board Geometry/Soldermask Top")
		(3 "B.Mask" user "Board Geometry/Soldermask Bottom")
		(17 "Dwgs.User" user "User.Drawings")
		(19 "Cmts.User" user "User.Comments")
		(21 "Eco1.User" user "User.Eco1")
		(23 "Eco2.User" user "User.Eco2")
		(25 "Edge.Cuts" user "Board Geometry/Outline")
		(27 "Margin" user)
		(31 "F.CrtYd" user "Package Geometry/Place Bound Top")
		(29 "B.CrtYd" user "Package Geometry/Place Bound Bottom")
		(35 "F.Fab" user "Ref Des/Assembly Top")
		(33 "B.Fab" user "Ref Des/Assembly Bottom")
	)
	(footprint ""
		(layer "B.Cu")
		(at 144.3228 -13.765022 90)
		(property "Reference" "R6033"
			(at 0 0 90)
			(layer "B.SilkS")
			(hide yes)
			(effects
				(font
					(size 1.27 1.27)
				)
				(justify mirror)
			)
		)
		(property "Value" ""
			(at 0 0 90)
			(layer "B.Fab")
			(effects
				(font
					(size 1.27 1.27)
				)
				(justify mirror)
			)
		)
		(duplicate_pad_numbers_are_jumpers no)
		(fp_line
			(start 0.7874 -0.4064)
			(end -0.7874 -0.4064)
			(stroke
				(width 0.1524)
				(type default)
			)
			(layer "B.SilkS")
		)
		(fp_line
			(start -0.7874 -0.4064)
			(end -0.7874 0.4064)
			(stroke
				(width 0.1524)
				(type default)
			)
			(layer "B.SilkS")
		)
		(fp_line
			(start 0.7874 0.4064)
			(end 0.7874 -0.4064)
			(stroke
				(width 0.1524)
				(type default)
			)
			(layer "B.SilkS")
		)
		(fp_line
			(start -0.7874 0.4064)
			(end 0.7874 0.4064)
			(stroke
				(width 0.1524)
				(type default)
			)
			(layer "B.SilkS")
		)
		(fp_line
			(start 0.67945 -0.305054)
			(end 0.12065 -0.305054)
			(stroke
				(width 0.1)
				(type default)
			)
			(layer "B.Fab")
		)
		(fp_line
			(start 0.12065 -0.305054)
			(end 0.12065 -0.2794)
			(stroke
				(width 0.1)
				(type default)
			)
			(layer "B.Fab")
		)
		(fp_line
			(start -0.12065 -0.3048)
			(end -0.67945 -0.3048)
			(stroke
				(width 0.1)
				(type default)
			)
			(layer "B.Fab")
		)
		(fp_line
			(start -0.67945 -0.3048)
			(end -0.67945 0.3048)
			(stroke
				(width 0.1)
				(type default)
			)
			(layer "B.Fab")
		)
		(fp_line
			(start 0.12065 -0.2794)
			(end -0.12065 -0.2794)
			(stroke
				(width 0.1)
				(type default)
			)
			(layer "B.Fab")
		)
		(fp_line
			(start -0.12065 -0.2794)
			(end -0.12065 -0.3048)
			(stroke
				(width 0.1)
				(type default)
			)
			(layer "B.Fab")
		)
		(fp_line
			(start 0.12065 0.2794)
			(end 0.12065 0.3048)
			(stroke
				(width 0.1)
				(type default)
			)
			(layer "B.Fab")
		)
		(fp_line
			(start -0.120396 0.2794)
			(end 0.12065 0.2794)
			(stroke
				(width 0.1)
				(type default)
			)
			(layer "B.Fab")
		)
		(fp_line
			(start 0.67945 0.3048)
			(end 0.67945 -0.305054)
			(stroke
				(width 0.1)
				(type default)
			)
			(layer "B.Fab")
		)
		(fp_line
			(start 0.12065 0.3048)
			(end 0.67945 0.3048)
			(stroke
				(width 0.1)
				(type default)
			)
			(layer "B.Fab")
		)
		(fp_line
			(start -0.120396 0.3048)
			(end -0.120396 0.2794)
			(stroke
				(width 0.1)
				(type default)
			)
			(layer "B.Fab")
		)
		(fp_line
			(start -0.67945 0.3048)
			(end -0.120396 0.3048)
			(stroke
				(width 0.1)
				(type default)
			)
			(layer "B.Fab")
		)
		(pad "1" smd circle
			(at 0.40005 0 270)
			(size 0 0)
			(layers "B.Cu" "B.Mask" "B.Paste")
			(net "RST_MB_STBY_N")
		)
		(pad "2" smd circle
			(at -0.40005 0 270)
			(size 0 0)
			(layers "B.Cu" "B.Mask" "B.Paste")
			(net "RST_MB_STBY_R_N")
		)
	)
	(footprint ""
		(layer "B.Cu")
		(at 288.200846 -420.38143 90)
		(property "Reference" "C2329"
			(at 0 0 90)
			(layer "B.SilkS")
			(hide yes)
			(effects
				(font
					(size 1.27 1.27)
				)
				(justify mirror)
			)
		)
		(property "Value" ""
			(at 0 0 90)
			(layer "B.Fab")
			(effects
				(font
					(size 1.27 1.27)
				)
				(justify mirror)
			)
		)
		(duplicate_pad_numbers_are_jumpers no)
		(fp_line
			(start 0.7874 -0.4064)
			(end -0.7874 -0.4064)
			(stroke
				(width 0.1524)
				(type default)
			)
			(layer "B.SilkS")
		)
		(fp_line
			(start -0.7874 -0.4064)
			(end -0.7874 0.4064)
			(stroke
				(width 0.1524)
				(type default)
			)
			(layer "B.SilkS")
		)
		(fp_line
			(start 0.7874 0.4064)
			(end 0.7874 -0.4064)
			(stroke
				(width 0.1524)
				(type default)
			)
			(layer "B.SilkS")
		)
		(fp_line
			(start -0.7874 0.4064)
			(end 0.7874 0.4064)
			(stroke
				(width 0.1524)
				(type default)
			)
			(layer "B.SilkS")
		)
		(fp_line
			(start 0.67945 -0.305054)
			(end 0.12065 -0.305054)
			(stroke
				(width 0.1)
				(type default)
			)
			(layer "B.Fab")
		)
		(fp_line
			(start 0.12065 -0.305054)
			(end 0.12065 -0.2794)
			(stroke
				(width 0.1)
				(type default)
			)
			(layer "B.Fab")
		)
		(fp_line
			(start -0.12065 -0.3048)
			(end -0.67945 -0.3048)
			(stroke
				(width 0.1)
				(type default)
			)
			(layer "B.Fab")
		)
		(fp_line
			(start -0.67945 -0.3048)
			(end -0.67945 0.3048)
			(stroke
				(width 0.1)
				(type default)
			)
			(layer "B.Fab")
		)
		(fp_line
			(start 0.12065 -0.2794)
			(end -0.12065 -0.2794)
			(stroke
				(width 0.1)
				(type default)
			)
			(layer "B.Fab")
		)
		(fp_line
			(start -0.12065 -0.2794)
			(end -0.12065 -0.3048)
			(stroke
				(width 0.1)
				(type default)
			)
			(layer "B.Fab")
		)
		(fp_line
			(start 0.12065 0.2794)
			(end 0.12065 0.3048)
			(stroke
				(width 0.1)
				(type default)
			)
			(layer "B.Fab")
		)
		(fp_line
			(start -0.120396 0.2794)
			(end 0.12065 0.2794)
			(stroke
				(width 0.1)
				(type default)
			)
			(layer "B.Fab")
		)
		(fp_line
			(start 0.67945 0.3048)
			(end 0.67945 -0.305054)
			(stroke
				(width 0.1)
				(type default)
			)
			(layer "B.Fab")
		)
		(fp_line
			(start 0.12065 0.3048)
			(end 0.67945 0.3048)
			(stroke
				(width 0.1)
				(type default)
			)
			(layer "B.Fab")
		)
		(fp_line
			(start -0.120396 0.3048)
			(end -0.120396 0.2794)
			(stroke
				(width 0.1)
				(type default)
			)
			(layer "B.Fab")
		)
		(fp_line
			(start -0.67945 0.3048)
			(end -0.120396 0.3048)
			(stroke
				(width 0.1)
				(type default)
			)
			(layer "B.Fab")
		)
		(pad "1" smd circle
			(at 0.40005 0 270)
			(size 0 0)
			(layers "B.Cu" "B.Mask" "B.Paste")
			(net "P3V3_9ZXL045_P0_VDD")
		)
		(pad "2" smd circle
			(at -0.40005 0 270)
			(size 0 0)
			(layers "B.Cu" "B.Mask" "B.Paste")
			(net "GND")
		)
	)
	(footprint ""
		(layer "B.Cu")
		(at 47.17288 -385.50088 -90)
		(property "Reference" "C186"
			(at 0 0 90)
			(layer "B.SilkS")
			(hide yes)
			(effects
				(font
					(size 1.27 1.27)
				)
				(justify mirror)
			)
		)
		(property "Value" ""
			(at 0 0 90)
			(layer "B.Fab")
			(effects
				(font
					(size 1.27 1.27)
				)
				(justify mirror)
			)
		)
		(duplicate_pad_numbers_are_jumpers no)
		(fp_line
			(start -0.299974 0.150114)
			(end 0.299974 0.150114)
			(stroke
				(width 0.1)
				(type default)
			)
			(layer "B.Fab")
		)
		(fp_line
			(start 0.299974 0.150114)
			(end 0.299974 -0.150114)
			(stroke
				(width 0.1)
				(type default)
			)
			(layer "B.Fab")
		)
		(fp_line
			(start -0.299974 -0.150114)
			(end -0.299974 0.150114)
			(stroke
				(width 0.1)
				(type default)
			)
			(layer "B.Fab")
		)
		(fp_line
			(start 0.299974 -0.150114)
			(end -0.299974 -0.150114)
			(stroke
				(width 0.1)
				(type default)
			)
			(layer "B.Fab")
		)
		(pad "1" smd rect
			(at 0.2667 0 90)
			(size 0.3048 0.381)
			(layers "B.Cu" "B.Mask" "B.Paste")
			(net "P0V9_CPU1_RT0_2A")
		)
		(pad "2" smd rect
			(at -0.2667 0 90)
			(size 0.3048 0.381)
			(layers "B.Cu" "B.Mask" "B.Paste")
			(net "GND")
		)
	)
)
